(kicad_pcb
	(version 20260206)
	(generator "pcbnew")
	(generator_version "10.0")
	(general
		(thickness 1.6)
		(legacy_teardrops no)
	)
	(paper "A4")
	(title_block
		(title "04192023_DAF0TMB3IC0_F0TG_MB_C_brd_V02_OCP.brd")
		(comment 1 "Grand Teton / footprint 3955 of 8354 (U25), pads 4110-4221 of 6102")
	)
	(layers
		(0 "F.Cu" signal "TOP")
		(4 "In1.Cu" signal "GND")
		(6 "In2.Cu" signal "IN1")
		(8 "In3.Cu" signal "GND1")
		(10 "In4.Cu" signal "IN2")
		(12 "In5.Cu" signal "GND2")
		(14 "In6.Cu" signal "IN3")
		(16 "In7.Cu" signal "GND3")
		(18 "In8.Cu" signal "VCC")
		(20 "In9.Cu" signal "VCC1")
		(22 "In10.Cu" signal "GND4")
		(24 "In11.Cu" signal "IN4")
		(26 "In12.Cu" signal "GND5")
		(28 "In13.Cu" signal "IN5")
		(30 "In14.Cu" signal "GND6")
		(32 "In15.Cu" signal "IN6")
		(34 "In16.Cu" signal "GND7")
		(2 "B.Cu" signal "BOTTOM")
		(9 "F.Adhes" user "F.Adhesive")
		(11 "B.Adhes" user "B.Adhesive")
		(13 "F.Paste" user "Package Geometry/Pastemask Top")
		(15 "B.Paste" user "Package Geometry/Pastemask Bottom")
		(5 "F.SilkS" user "Ref Des/Silkscreen Top")
		(7 "B.SilkS" user "Ref Des/Silkscreen Bottom")
		(1 "F.Mask" user "Board Geometry/Soldermask Top")
		(3 "B.Mask" user "Board Geometry/Soldermask Bottom")
		(17 "Dwgs.User" user "User.Drawings")
		(19 "Cmts.User" user "User.Comments")
		(21 "Eco1.User" user "User.Eco1")
		(23 "Eco2.User" user "User.Eco2")
		(25 "Edge.Cuts" user "Board Geometry/Outline")
		(27 "Margin" user)
		(31 "F.CrtYd" user "Package Geometry/Place Bound Top")
		(29 "B.CrtYd" user "Package Geometry/Place Bound Bottom")
		(35 "F.Fab" user "Ref Des/Assembly Top")
		(33 "B.Fab" user "Ref Des/Assembly Bottom")
	)
	(footprint ""
		(layer "F.Cu")
		(at 359.867962 -258.880102 180)
		(property "Reference" "U25"
			(at -45.78477 -62.086744 0)
			(unlocked yes)
			(layer "F.SilkS")
			(effects
				(font
					(size 0.7874 0.5842)
					(thickness 0.1524)
				)
			)
		)
		(property "Value" ""
			(at 0 0 180)
			(layer "F.Fab")
			(effects
				(font
					(size 1.27 1.27)
				)
			)
		)
		(duplicate_pad_numbers_are_jumpers no)
		(pad "CW6" smd circle
			(at -29.75991 28.710128 180)
			(size 0.450088 0.450088)
			(layers "F.Cu" "F.Mask" "F.Paste")
			(net "GND")
		)
		(pad "CW7" smd circle
			(at -28.82011 28.710128 180)
			(size 0.450088 0.450088)
			(layers "F.Cu" "F.Mask" "F.Paste")
			(net "M_K_CPU0_SB_DQ<21>")
		)
		(pad "CW8" smd circle
			(at -27.880056 28.710128 180)
			(size 0.450088 0.450088)
			(layers "F.Cu" "F.Mask" "F.Paste")
			(net "GND")
		)
		(pad "CW9" smd circle
			(at -26.940002 28.710128 180)
			(size 0.450088 0.450088)
			(layers "F.Cu" "F.Mask" "F.Paste")
			(net "M_L_CPU0_SB_DQ<22>")
		)
		(pad "CW10" smd circle
			(at -25.999948 28.710128 180)
			(size 0.450088 0.450088)
			(layers "F.Cu" "F.Mask" "F.Paste")
			(net "M_L_CPU0_SB_DQ<21>")
		)
		(pad "CW11" smd circle
			(at -25.059894 28.710128 180)
			(size 0.450088 0.450088)
			(layers "F.Cu" "F.Mask" "F.Paste")
			(net "PVDD11_S3_P0")
		)
		(pad "CW12" smd circle
			(at -24.120094 28.710128 180)
			(size 0.450088 0.450088)
			(layers "F.Cu" "F.Mask" "F.Paste")
			(net "M_H_CPU0_SB_DQ<22>")
		)
		(pad "CW13" smd circle
			(at -23.18004 28.710128 180)
			(size 0.450088 0.450088)
			(layers "F.Cu" "F.Mask" "F.Paste")
			(net "GND")
		)
		(pad "CW14" smd circle
			(at -22.239986 28.710128 180)
			(size 0.450088 0.450088)
			(layers "F.Cu" "F.Mask" "F.Paste")
			(net "M_H_CPU0_SB_DQ<21>")
		)
		(pad "CW15" smd circle
			(at -21.299932 28.710128 180)
			(size 0.450088 0.450088)
			(layers "F.Cu" "F.Mask" "F.Paste")
			(net "GND")
		)
		(pad "CW16" smd circle
			(at -20.359878 28.710128 180)
			(size 0.450088 0.450088)
			(layers "F.Cu" "F.Mask" "F.Paste")
			(net "M_J_CPU0_SB_DQ<22>")
		)
		(pad "CW17" smd circle
			(at -19.420078 28.710128 180)
			(size 0.450088 0.450088)
			(layers "F.Cu" "F.Mask" "F.Paste")
			(net "M_J_CPU0_SB_DQ<21>")
		)
		(pad "CW18" smd circle
			(at -18.480024 28.710128 180)
			(size 0.450088 0.450088)
			(layers "F.Cu" "F.Mask" "F.Paste")
			(net "PVDD11_S3_P0")
		)
		(pad "CW19" smd circle
			(at -17.53997 28.710128 180)
			(size 0.450088 0.450088)
			(layers "F.Cu" "F.Mask" "F.Paste")
			(net "M_I_CPU0_SB_DQ<22>")
		)
		(pad "CW20" smd circle
			(at -16.599916 28.710128 180)
			(size 0.450088 0.450088)
			(layers "F.Cu" "F.Mask" "F.Paste")
			(net "GND")
		)
		(pad "CW21" smd circle
			(at -15.660116 28.710128 180)
			(size 0.450088 0.450088)
			(layers "F.Cu" "F.Mask" "F.Paste")
			(net "M_I_CPU0_SB_DQ<21>")
		)
		(pad "CW22" smd circle
			(at -14.720062 28.710128 180)
			(size 0.450088 0.450088)
			(layers "F.Cu" "F.Mask" "F.Paste")
			(net "GND")
		)
		(pad "CW23" smd circle
			(at -13.780008 28.710128 180)
			(size 0.450088 0.450088)
			(layers "F.Cu" "F.Mask" "F.Paste")
			(net "P5E_CPU0_P3_RX_DP<12>")
		)
		(pad "CW24" smd circle
			(at -12.839954 28.710128 180)
			(size 0.450088 0.450088)
			(layers "F.Cu" "F.Mask" "F.Paste")
			(net "P5E_CPU0_P3_RX_DN<12>")
		)
		(pad "CW25" smd circle
			(at -11.8999 28.710128 180)
			(size 0.450088 0.450088)
			(layers "F.Cu" "F.Mask" "F.Paste")
			(net "GND")
		)
		(pad "CW26" smd circle
			(at -10.9601 28.710128 180)
			(size 0.450088 0.450088)
			(layers "F.Cu" "F.Mask" "F.Paste")
			(net "P5E_CPU0_P3_RX_DP<9>")
		)
		(pad "CW27" smd circle
			(at -10.020046 28.710128 180)
			(size 0.450088 0.450088)
			(layers "F.Cu" "F.Mask" "F.Paste")
			(net "P5E_CPU0_P3_RX_DN<9>")
		)
		(pad "CW28" smd circle
			(at -9.079992 28.710128 180)
			(size 0.450088 0.450088)
			(layers "F.Cu" "F.Mask" "F.Paste")
			(net "GND")
		)
		(pad "CW29" smd circle
			(at -8.139938 28.710128 180)
			(size 0.450088 0.450088)
			(layers "F.Cu" "F.Mask" "F.Paste")
			(net "P5E_CPU0_P3_RX_DP<6>")
		)
		(pad "CW30" smd circle
			(at -7.199884 28.710128 180)
			(size 0.450088 0.450088)
			(layers "F.Cu" "F.Mask" "F.Paste")
			(net "P5E_CPU0_P3_RX_DN<6>")
		)
		(pad "CW31" smd circle
			(at -6.260084 28.710128 180)
			(size 0.450088 0.450088)
			(layers "F.Cu" "F.Mask" "F.Paste")
			(net "GND")
		)
		(pad "CW32" smd circle
			(at -5.32003 28.710128 180)
			(size 0.450088 0.450088)
			(layers "F.Cu" "F.Mask" "F.Paste")
			(net "P5E_CPU0_P3_RX_DP<3>")
		)
		(pad "CW33" smd circle
			(at -4.379976 28.710128 180)
			(size 0.450088 0.450088)
			(layers "F.Cu" "F.Mask" "F.Paste")
			(net "P5E_CPU0_P3_RX_DN<3>")
		)
		(pad "CW34" smd circle
			(at -3.439922 28.710128 180)
			(size 0.450088 0.450088)
			(layers "F.Cu" "F.Mask" "F.Paste")
			(net "GND")
		)
		(pad "CW35" smd circle
			(at -2.500122 28.710128 180)
			(size 0.450088 0.450088)
			(layers "F.Cu" "F.Mask" "F.Paste")
			(net "GND")
		)
		(pad "CW36" smd circle
			(at -1.560068 28.710128 180)
			(size 0.450088 0.450088)
			(layers "F.Cu" "F.Mask" "F.Paste")
			(net "GND")
		)
		(pad "CW40" smd circle
			(at 1.260094 28.710128 180)
			(size 0.450088 0.450088)
			(layers "F.Cu" "F.Mask" "F.Paste")
			(net "GND")
		)
		(pad "CW41" smd circle
			(at 2.199894 28.710128 180)
			(size 0.450088 0.450088)
			(layers "F.Cu" "F.Mask" "F.Paste")
			(net "GND")
		)
		(pad "CW42" smd circle
			(at 3.139948 28.710128 180)
			(size 0.450088 0.450088)
			(layers "F.Cu" "F.Mask" "F.Paste")
			(net "GND")
		)
		(pad "CW43" smd circle
			(at 4.080002 28.710128 180)
			(size 0.450088 0.450088)
			(layers "F.Cu" "F.Mask" "F.Paste")
			(net "P5E_CPU0_P1_TX_DN<12>")
		)
		(pad "CW44" smd circle
			(at 5.020056 28.710128 180)
			(size 0.450088 0.450088)
			(layers "F.Cu" "F.Mask" "F.Paste")
			(net "P5E_CPU0_P1_TX_DP<12>")
		)
		(pad "CW45" smd circle
			(at 5.96011 28.710128 180)
			(size 0.450088 0.450088)
			(layers "F.Cu" "F.Mask" "F.Paste")
			(net "GND")
		)
		(pad "CW46" smd circle
			(at 6.89991 28.710128 180)
			(size 0.450088 0.450088)
			(layers "F.Cu" "F.Mask" "F.Paste")
			(net "P5E_CPU0_P1_TX_DN<9>")
		)
		(pad "CW47" smd circle
			(at 7.839964 28.710128 180)
			(size 0.450088 0.450088)
			(layers "F.Cu" "F.Mask" "F.Paste")
			(net "P5E_CPU0_P1_TX_DP<9>")
		)
		(pad "CW48" smd circle
			(at 8.780018 28.710128 180)
			(size 0.450088 0.450088)
			(layers "F.Cu" "F.Mask" "F.Paste")
			(net "GND")
		)
		(pad "CW49" smd circle
			(at 9.720072 28.710128 180)
			(size 0.450088 0.450088)
			(layers "F.Cu" "F.Mask" "F.Paste")
			(net "P5E_CPU0_P1_TX_DN<6>")
		)
		(pad "CW50" smd circle
			(at 10.659872 28.710128 180)
			(size 0.450088 0.450088)
			(layers "F.Cu" "F.Mask" "F.Paste")
			(net "P5E_CPU0_P1_TX_DP<6>")
		)
		(pad "CW51" smd circle
			(at 11.599926 28.710128 180)
			(size 0.450088 0.450088)
			(layers "F.Cu" "F.Mask" "F.Paste")
			(net "GND")
		)
		(pad "CW52" smd circle
			(at 12.53998 28.710128 180)
			(size 0.450088 0.450088)
			(layers "F.Cu" "F.Mask" "F.Paste")
			(net "P5E_CPU0_P1_TX_DN<3>")
		)
		(pad "CW53" smd circle
			(at 13.480034 28.710128 180)
			(size 0.450088 0.450088)
			(layers "F.Cu" "F.Mask" "F.Paste")
			(net "P5E_CPU0_P1_TX_DP<3>")
		)
		(pad "CW54" smd circle
			(at 14.420088 28.710128 180)
			(size 0.450088 0.450088)
			(layers "F.Cu" "F.Mask" "F.Paste")
			(net "GND")
		)
		(pad "CW55" smd circle
			(at 15.359888 28.710128 180)
			(size 0.450088 0.450088)
			(layers "F.Cu" "F.Mask" "F.Paste")
			(net "M_C_CPU0_SB_DQ<21>")
		)
		(pad "CW56" smd circle
			(at 16.299942 28.710128 180)
			(size 0.450088 0.450088)
			(layers "F.Cu" "F.Mask" "F.Paste")
			(net "GND")
		)
		(pad "CW57" smd circle
			(at 17.239996 28.710128 180)
			(size 0.450088 0.450088)
			(layers "F.Cu" "F.Mask" "F.Paste")
			(net "M_C_CPU0_SB_DQ<22>")
		)
		(pad "CW58" smd circle
			(at 18.18005 28.710128 180)
			(size 0.450088 0.450088)
			(layers "F.Cu" "F.Mask" "F.Paste")
			(net "PVDDIO_P0")
		)
		(pad "CW59" smd circle
			(at 19.120104 28.710128 180)
			(size 0.450088 0.450088)
			(layers "F.Cu" "F.Mask" "F.Paste")
			(net "M_D_CPU0_SB_DQ<21>")
		)
		(pad "CW60" smd circle
			(at 20.059904 28.710128 180)
			(size 0.450088 0.450088)
			(layers "F.Cu" "F.Mask" "F.Paste")
			(net "M_D_CPU0_SB_DQ<22>")
		)
		(pad "CW61" smd circle
			(at 20.999958 28.710128 180)
			(size 0.450088 0.450088)
			(layers "F.Cu" "F.Mask" "F.Paste")
			(net "GND")
		)
		(pad "CW62" smd circle
			(at 21.940012 28.710128 180)
			(size 0.450088 0.450088)
			(layers "F.Cu" "F.Mask" "F.Paste")
			(net "M_B_CPU0_SB_DQ<21>")
		)
		(pad "CW63" smd circle
			(at 22.880066 28.710128 180)
			(size 0.450088 0.450088)
			(layers "F.Cu" "F.Mask" "F.Paste")
			(net "GND")
		)
		(pad "CW64" smd circle
			(at 23.82012 28.710128 180)
			(size 0.450088 0.450088)
			(layers "F.Cu" "F.Mask" "F.Paste")
			(net "M_B_CPU0_SB_DQ<22>")
		)
		(pad "CW65" smd circle
			(at 24.75992 28.710128 180)
			(size 0.450088 0.450088)
			(layers "F.Cu" "F.Mask" "F.Paste")
			(net "PVDDIO_P0")
		)
		(pad "CW66" smd circle
			(at 25.699974 28.710128 180)
			(size 0.450088 0.450088)
			(layers "F.Cu" "F.Mask" "F.Paste")
			(net "M_F_CPU0_SB_DQ<21>")
		)
		(pad "CW67" smd circle
			(at 26.640028 28.710128 180)
			(size 0.450088 0.450088)
			(layers "F.Cu" "F.Mask" "F.Paste")
			(net "M_F_CPU0_SB_DQ<22>")
		)
		(pad "CW68" smd circle
			(at 27.580082 28.710128 180)
			(size 0.450088 0.450088)
			(layers "F.Cu" "F.Mask" "F.Paste")
			(net "GND")
		)
		(pad "CW69" smd circle
			(at 28.519882 28.710128 180)
			(size 0.450088 0.450088)
			(layers "F.Cu" "F.Mask" "F.Paste")
			(net "M_E_CPU0_SB_DQ<21>")
		)
		(pad "CW70" smd circle
			(at 29.459936 28.710128 180)
			(size 0.450088 0.450088)
			(layers "F.Cu" "F.Mask" "F.Paste")
			(net "GND")
		)
		(pad "CW71" smd circle
			(at 30.39999 28.710128 180)
			(size 0.450088 0.450088)
			(layers "F.Cu" "F.Mask" "F.Paste")
			(net "M_E_CPU0_SB_DQ<22>")
		)
		(pad "CW72" smd circle
			(at 31.340044 28.710128 180)
			(size 0.450088 0.450088)
			(layers "F.Cu" "F.Mask" "F.Paste")
			(net "PVDDIO_P0")
		)
		(pad "CW73" smd circle
			(at 32.280098 28.710128 180)
			(size 0.450088 0.450088)
			(layers "F.Cu" "F.Mask" "F.Paste")
			(net "M_A_CPU0_SB_DQ<21>")
		)
		(pad "CW74" smd circle
			(at 33.219898 28.710128 180)
			(size 0.450088 0.450088)
			(layers "F.Cu" "F.Mask" "F.Paste")
			(net "M_A_CPU0_SB_DQ<22>")
		)
		(pad "CW75" smd circle
			(at 34.159952 28.710128 180)
			(size 0.450088 0.450088)
			(layers "F.Cu" "F.Mask" "F.Paste")
			(net "GND")
		)
		(pad "CY2" smd circle
			(at -33.990026 29.51988 180)
			(size 0.450088 0.450088)
			(layers "F.Cu" "F.Mask" "F.Paste")
			(net "M_G_CPU0_SB_DQ<24>")
		)
		(pad "CY3" smd circle
			(at -33.049972 29.51988 180)
			(size 0.450088 0.450088)
			(layers "F.Cu" "F.Mask" "F.Paste")
			(net "GND")
		)
		(pad "CY4" smd circle
			(at -32.109918 29.51988 180)
			(size 0.450088 0.450088)
			(layers "F.Cu" "F.Mask" "F.Paste")
			(net "M_G_CPU0_SB_DQ<23>")
		)
		(pad "CY5" smd circle
			(at -31.170118 29.51988 180)
			(size 0.450088 0.450088)
			(layers "F.Cu" "F.Mask" "F.Paste")
			(net "GND")
		)
		(pad "CY6" smd circle
			(at -30.230064 29.51988 180)
			(size 0.450088 0.450088)
			(layers "F.Cu" "F.Mask" "F.Paste")
			(net "M_K_CPU0_SB_DQ<24>")
		)
		(pad "CY7" smd circle
			(at -29.29001 29.51988 180)
			(size 0.450088 0.450088)
			(layers "F.Cu" "F.Mask" "F.Paste")
			(net "M_K_CPU0_SB_DQ<23>")
		)
		(pad "CY8" smd circle
			(at -28.349956 29.51988 180)
			(size 0.450088 0.450088)
			(layers "F.Cu" "F.Mask" "F.Paste")
			(net "GND")
		)
		(pad "CY9" smd circle
			(at -27.409902 29.51988 180)
			(size 0.450088 0.450088)
			(layers "F.Cu" "F.Mask" "F.Paste")
			(net "M_L_CPU0_SB_DQ<24>")
		)
		(pad "CY10" smd circle
			(at -26.470102 29.51988 180)
			(size 0.450088 0.450088)
			(layers "F.Cu" "F.Mask" "F.Paste")
			(net "GND")
		)
		(pad "CY11" smd circle
			(at -25.530048 29.51988 180)
			(size 0.450088 0.450088)
			(layers "F.Cu" "F.Mask" "F.Paste")
			(net "M_L_CPU0_SB_DQ<23>")
		)
		(pad "CY12" smd circle
			(at -24.589994 29.51988 180)
			(size 0.450088 0.450088)
			(layers "F.Cu" "F.Mask" "F.Paste")
			(net "GND")
		)
		(pad "CY13" smd circle
			(at -23.64994 29.51988 180)
			(size 0.450088 0.450088)
			(layers "F.Cu" "F.Mask" "F.Paste")
			(net "M_H_CPU0_SB_DQ<24>")
		)
		(pad "CY14" smd circle
			(at -22.709886 29.51988 180)
			(size 0.450088 0.450088)
			(layers "F.Cu" "F.Mask" "F.Paste")
			(net "M_H_CPU0_SB_DQ<23>")
		)
		(pad "CY15" smd circle
			(at -21.770086 29.51988 180)
			(size 0.450088 0.450088)
			(layers "F.Cu" "F.Mask" "F.Paste")
			(net "GND")
		)
		(pad "CY16" smd circle
			(at -20.830032 29.51988 180)
			(size 0.450088 0.450088)
			(layers "F.Cu" "F.Mask" "F.Paste")
			(net "M_J_CPU0_SB_DQ<24>")
		)
		(pad "CY17" smd circle
			(at -19.889978 29.51988 180)
			(size 0.450088 0.450088)
			(layers "F.Cu" "F.Mask" "F.Paste")
			(net "GND")
		)
		(pad "CY18" smd circle
			(at -18.949924 29.51988 180)
			(size 0.450088 0.450088)
			(layers "F.Cu" "F.Mask" "F.Paste")
			(net "M_J_CPU0_SB_DQ<23>")
		)
		(pad "CY19" smd circle
			(at -18.010124 29.51988 180)
			(size 0.450088 0.450088)
			(layers "F.Cu" "F.Mask" "F.Paste")
			(net "GND")
		)
		(pad "CY20" smd circle
			(at -17.07007 29.51988 180)
			(size 0.450088 0.450088)
			(layers "F.Cu" "F.Mask" "F.Paste")
			(net "M_I_CPU0_SB_DQ<24>")
		)
		(pad "CY21" smd circle
			(at -16.130016 29.51988 180)
			(size 0.450088 0.450088)
			(layers "F.Cu" "F.Mask" "F.Paste")
			(net "M_I_CPU0_SB_DQ<23>")
		)
		(pad "CY22" smd circle
			(at -15.189962 29.51988 180)
			(size 0.450088 0.450088)
			(layers "F.Cu" "F.Mask" "F.Paste")
			(net "PVDD11_S3_P0")
		)
		(pad "CY23" smd circle
			(at -14.249908 29.51988 180)
			(size 0.450088 0.450088)
			(layers "F.Cu" "F.Mask" "F.Paste")
			(net "GND")
		)
		(pad "CY24" smd circle
			(at -13.310108 29.51988 180)
			(size 0.450088 0.450088)
			(layers "F.Cu" "F.Mask" "F.Paste")
			(net "GND")
		)
		(pad "CY25" smd circle
			(at -12.370054 29.51988 180)
			(size 0.450088 0.450088)
			(layers "F.Cu" "F.Mask" "F.Paste")
			(net "GND")
		)
		(pad "CY26" smd circle
			(at -11.43 29.51988 180)
			(size 0.450088 0.450088)
			(layers "F.Cu" "F.Mask" "F.Paste")
			(net "GND")
		)
		(pad "CY27" smd circle
			(at -10.489946 29.51988 180)
			(size 0.450088 0.450088)
			(layers "F.Cu" "F.Mask" "F.Paste")
			(net "GND")
		)
		(pad "CY28" smd circle
			(at -9.549892 29.51988 180)
			(size 0.450088 0.450088)
			(layers "F.Cu" "F.Mask" "F.Paste")
			(net "GND")
		)
		(pad "CY29" smd circle
			(at -8.610092 29.51988 180)
			(size 0.450088 0.450088)
			(layers "F.Cu" "F.Mask" "F.Paste")
			(net "GND")
		)
		(pad "CY30" smd circle
			(at -7.670038 29.51988 180)
			(size 0.450088 0.450088)
			(layers "F.Cu" "F.Mask" "F.Paste")
			(net "GND")
		)
		(pad "CY31" smd circle
			(at -6.729984 29.51988 180)
			(size 0.450088 0.450088)
			(layers "F.Cu" "F.Mask" "F.Paste")
			(net "GND")
		)
		(pad "CY32" smd circle
			(at -5.78993 29.51988 180)
			(size 0.450088 0.450088)
			(layers "F.Cu" "F.Mask" "F.Paste")
			(net "GND")
		)
		(pad "CY33" smd circle
			(at -4.849876 29.51988 180)
			(size 0.450088 0.450088)
			(layers "F.Cu" "F.Mask" "F.Paste")
			(net "GND")
		)
		(pad "CY34" smd circle
			(at -3.910076 29.51988 180)
			(size 0.450088 0.450088)
			(layers "F.Cu" "F.Mask" "F.Paste")
			(net "GND")
		)
		(pad "CY35" smd circle
			(at -2.970022 29.51988 180)
			(size 0.450088 0.450088)
			(layers "F.Cu" "F.Mask" "F.Paste")
			(net "P5E_CPU0_P3_RX_DP<1>")
		)
		(pad "CY36" smd circle
			(at -2.029968 29.51988 180)
			(size 0.450088 0.450088)
			(layers "F.Cu" "F.Mask" "F.Paste")
			(net "P5E_CPU0_P3_RX_DN<1>")
		)
		(pad "CY37" smd circle
			(at -1.089914 29.51988 180)
			(size 0.450088 0.450088)
			(layers "F.Cu" "F.Mask" "F.Paste")
			(net "GND")
		)
		(pad "CY39" smd circle
			(at 0.78994 29.51988 180)
			(size 0.450088 0.450088)
			(layers "F.Cu" "F.Mask" "F.Paste")
			(net "GND")
		)
		(pad "CY40" smd circle
			(at 1.729994 29.51988 180)
			(size 0.450088 0.450088)
			(layers "F.Cu" "F.Mask" "F.Paste")
			(net "P5E_CPU0_P1_TX_DN<14>")
		)
		(pad "CY41" smd circle
			(at 2.670048 29.51988 180)
			(size 0.450088 0.450088)
			(layers "F.Cu" "F.Mask" "F.Paste")
			(net "P5E_CPU0_P1_TX_DP<14>")
		)
		(pad "CY42" smd circle
			(at 3.610102 29.51988 180)
			(size 0.450088 0.450088)
			(layers "F.Cu" "F.Mask" "F.Paste")
			(net "GND")
		)
		(pad "CY43" smd circle
			(at 4.549902 29.51988 180)
			(size 0.450088 0.450088)
			(layers "F.Cu" "F.Mask" "F.Paste")
			(net "GND")
		)
		(pad "CY44" smd circle
			(at 5.489956 29.51988 180)
			(size 0.450088 0.450088)
			(layers "F.Cu" "F.Mask" "F.Paste")
			(net "GND")
		)
		(pad "CY45" smd circle
			(at 6.43001 29.51988 180)
			(size 0.450088 0.450088)
			(layers "F.Cu" "F.Mask" "F.Paste")
			(net "GND")
		)
		(pad "CY46" smd circle
			(at 7.370064 29.51988 180)
			(size 0.450088 0.450088)
			(layers "F.Cu" "F.Mask" "F.Paste")
			(net "GND")
		)
		(pad "CY47" smd circle
			(at 8.310118 29.51988 180)
			(size 0.450088 0.450088)
			(layers "F.Cu" "F.Mask" "F.Paste")
			(net "GND")
		)
	)
)
